(kicad_pcb
	(version 20260206)
	(generator "pcbnew")
	(generator_version "10.0")
	(general
		(thickness 1.6)
		(legacy_teardrops no)
	)
	(paper "A4")
	(title_block
		(title "Wiwynn_Tioga_Pass_MB.brd")
		(comment 1 "Tioga Pass / footprints 2078-2083 of 4770")
	)
	(layers
		(0 "F.Cu" signal "TOP")
		(4 "In1.Cu" signal "L2GND")
		(6 "In2.Cu" signal "L3")
		(8 "In3.Cu" signal "L4GND")
		(10 "In4.Cu" signal "L5")
		(12 "In5.Cu" signal "L6GND")
		(14 "In6.Cu" signal "L7VCC")
		(16 "In7.Cu" signal "L8VCC")
		(18 "In8.Cu" signal "L9GND")
		(20 "In9.Cu" signal "L10")
		(22 "In10.Cu" signal "L11GND")
		(24 "In11.Cu" signal "L12")
		(26 "In12.Cu" signal "L13GND")
		(2 "B.Cu" signal "BOTTOM")
		(9 "F.Adhes" user "F.Adhesive")
		(11 "B.Adhes" user "B.Adhesive")
		(13 "F.Paste" user "Package Geometry/Pastemask Top")
		(15 "B.Paste" user "Package Geometry/Pastemask Bottom")
		(5 "F.SilkS" user "Ref Des/Silkscreen Top")
		(7 "B.SilkS" user "Ref Des/Silkscreen Bottom")
		(1 "F.Mask" user "Board Geometry/Soldermask Top")
		(3 "B.Mask" user "Board Geometry/Soldermask Bottom")
		(17 "Dwgs.User" user "User.Drawings")
		(19 "Cmts.User" user "User.Comments")
		(21 "Eco1.User" user "User.Eco1")
		(23 "Eco2.User" user "User.Eco2")
		(25 "Edge.Cuts" user "Board Geometry/Outline")
		(27 "Margin" user)
		(31 "F.CrtYd" user "Package Geometry/Place Bound Top")
		(29 "B.CrtYd" user "Package Geometry/Place Bound Bottom")
		(35 "F.Fab" user "Ref Des/Assembly Top")
		(33 "B.Fab" user "Ref Des/Assembly Bottom")
	)
	(footprint ""
		(layer "F.Cu")
		(at 195.58 -12.923012 90)
		(property "Reference" "C4G3"
			(at 0 0 90)
			(layer "F.SilkS")
			(hide yes)
			(effects
				(font
					(size 1.27 1.27)
				)
			)
		)
		(property "Value" ""
			(at 0 0 90)
			(layer "F.Fab")
			(effects
				(font
					(size 1.27 1.27)
				)
			)
		)
		(duplicate_pad_numbers_are_jumpers no)
		(fp_poly
			(pts
				(xy 0.3048 -0.1016) (xy 0.3048 0.9906) (xy -0.3048 0.9906) (xy -0.3048 -0.1016)
			)
			(stroke
				(width 0)
				(type default)
			)
			(fill no)
			(layer "F.CrtYd")
		)
		(fp_line
			(start 0.3048 -0.1016)
			(end -0.3048 -0.1016)
			(stroke
				(width 0.1)
				(type default)
			)
			(layer "F.Fab")
		)
		(fp_line
			(start -0.3048 -0.1016)
			(end -0.3048 0.9906)
			(stroke
				(width 0.1)
				(type default)
			)
			(layer "F.Fab")
		)
		(fp_line
			(start 0.3048 0.9906)
			(end 0.3048 -0.1016)
			(stroke
				(width 0.1)
				(type default)
			)
			(layer "F.Fab")
		)
		(fp_line
			(start -0.3048 0.9906)
			(end 0.3048 0.9906)
			(stroke
				(width 0.1)
				(type default)
			)
			(layer "F.Fab")
		)
		(pad "1" smd rect
			(at 0 0 90)
			(size 0.508 0.508)
			(layers "F.Cu" "F.Mask" "F.Paste")
			(net "M_B_VREF")
		)
		(pad "2" smd rect
			(at 0 0.889 90)
			(size 0.508 0.508)
			(layers "F.Cu" "F.Mask" "F.Paste")
			(net "GND")
		)
		(zone
			(layer "F.Cu")
			(hatch none 0.5)
			(connect_pads
				(clearance 0)
			)
			(min_thickness 0.25)
			(keepout
				(tracks allowed)
				(vias not_allowed)
				(pads allowed)
				(copperpour not_allowed)
				(footprints allowed)
			)
			(placement
				(enabled no)
				(sheetname "")
			)
			(fill
				(thermal_gap 0.5)
				(thermal_bridge_width 0.5)
				(island_removal_mode 0)
			)
			(polygon
				(pts
					(xy 195.834 -12.669012) (xy 195.834 -13.177012) (xy 196.215 -13.177012) (xy 196.215 -12.669012)
				)
			)
		)
		(zone
			(layer "F.Cu")
			(hatch none 0.5)
			(connect_pads
				(clearance 0)
			)
			(min_thickness 0.25)
			(keepout
				(tracks not_allowed)
				(vias allowed)
				(pads allowed)
				(copperpour not_allowed)
				(footprints allowed)
			)
			(placement
				(enabled no)
				(sheetname "")
			)
			(fill
				(thermal_gap 0.5)
				(thermal_bridge_width 0.5)
				(island_removal_mode 0)
			)
			(polygon
				(pts
					(xy 196.215 -12.669012) (xy 196.215 -13.177012) (xy 195.834 -13.177012) (xy 195.834 -12.669012)
				)
			)
		)
	)
	(footprint ""
		(layer "F.Cu")
		(at 485.875076 -28.104084)
		(property "Reference" "R9F67"
			(at 0 0 0)
			(layer "F.SilkS")
			(hide yes)
			(effects
				(font
					(size 1.27 1.27)
				)
			)
		)
		(property "Value" ""
			(at 0 0 0)
			(layer "F.Fab")
			(effects
				(font
					(size 1.27 1.27)
				)
			)
		)
		(duplicate_pad_numbers_are_jumpers no)
		(fp_poly
			(pts
				(xy -0.2794 -0.1016) (xy 0.2794 -0.1016) (xy 0.2794 0.9906) (xy -0.2794 0.9906)
			)
			(stroke
				(width 0)
				(type default)
			)
			(fill no)
			(layer "F.CrtYd")
		)
		(fp_line
			(start -0.2794 -0.1016)
			(end -0.2794 0.9906)
			(stroke
				(width 0.1)
				(type default)
			)
			(layer "F.Fab")
		)
		(fp_line
			(start -0.2794 0.9906)
			(end 0.2794 0.9906)
			(stroke
				(width 0.1)
				(type default)
			)
			(layer "F.Fab")
		)
		(fp_line
			(start 0.2794 -0.1016)
			(end -0.2794 -0.1016)
			(stroke
				(width 0.1)
				(type default)
			)
			(layer "F.Fab")
		)
		(fp_line
			(start 0.2794 0.9906)
			(end 0.2794 -0.1016)
			(stroke
				(width 0.1)
				(type default)
			)
			(layer "F.Fab")
		)
		(pad "1" smd rect
			(at 0 0)
			(size 0.508 0.508)
			(layers "F.Cu" "F.Mask" "F.Paste")
			(net "SP2_BMC_CM_UART_RX_R1")
		)
		(pad "2" smd rect
			(at 0 0.889)
			(size 0.508 0.508)
			(layers "F.Cu" "F.Mask" "F.Paste")
			(net "SPA_MID_DBG_TX_R")
		)
		(zone
			(layer "F.Cu")
			(hatch none 0.5)
			(connect_pads
				(clearance 0)
			)
			(min_thickness 0.25)
			(keepout
				(tracks allowed)
				(vias not_allowed)
				(pads allowed)
				(copperpour not_allowed)
				(footprints allowed)
			)
			(placement
				(enabled no)
				(sheetname "")
			)
			(fill
				(thermal_gap 0.5)
				(thermal_bridge_width 0.5)
				(island_removal_mode 0)
			)
			(polygon
				(pts
					(xy 485.621076 -27.850084) (xy 486.129076 -27.850084) (xy 486.129076 -27.469084) (xy 485.621076 -27.469084)
				)
			)
		)
		(zone
			(layer "F.Cu")
			(hatch none 0.5)
			(connect_pads
				(clearance 0)
			)
			(min_thickness 0.25)
			(keepout
				(tracks not_allowed)
				(vias allowed)
				(pads allowed)
				(copperpour not_allowed)
				(footprints allowed)
			)
			(placement
				(enabled no)
				(sheetname "")
			)
			(fill
				(thermal_gap 0.5)
				(thermal_bridge_width 0.5)
				(island_removal_mode 0)
			)
			(polygon
				(pts
					(xy 485.621076 -27.469084) (xy 486.129076 -27.469084) (xy 486.129076 -27.850084) (xy 485.621076 -27.850084)
				)
			)
		)
	)
	(footprint ""
		(layer "F.Cu")
		(at 428.63008 -36.07435 -90)
		(property "Reference" "R1T27"
			(at 0 0 270)
			(layer "F.SilkS")
			(hide yes)
			(effects
				(font
					(size 1.27 1.27)
				)
			)
		)
		(property "Value" ""
			(at 0 0 270)
			(layer "F.Fab")
			(effects
				(font
					(size 1.27 1.27)
				)
			)
		)
		(duplicate_pad_numbers_are_jumpers no)
		(fp_poly
			(pts
				(xy -0.2794 -0.1016) (xy 0.2794 -0.1016) (xy 0.2794 0.9906) (xy -0.2794 0.9906)
			)
			(stroke
				(width 0)
				(type default)
			)
			(fill no)
			(layer "F.CrtYd")
		)
		(fp_line
			(start -0.2794 0.9906)
			(end 0.2794 0.9906)
			(stroke
				(width 0.1)
				(type default)
			)
			(layer "F.Fab")
		)
		(fp_line
			(start 0.2794 0.9906)
			(end 0.2794 -0.1016)
			(stroke
				(width 0.1)
				(type default)
			)
			(layer "F.Fab")
		)
		(fp_line
			(start -0.2794 -0.1016)
			(end -0.2794 0.9906)
			(stroke
				(width 0.1)
				(type default)
			)
			(layer "F.Fab")
		)
		(fp_line
			(start 0.2794 -0.1016)
			(end -0.2794 -0.1016)
			(stroke
				(width 0.1)
				(type default)
			)
			(layer "F.Fab")
		)
		(pad "1" smd rect
			(at 0 0 270)
			(size 0.508 0.508)
			(layers "F.Cu" "F.Mask" "F.Paste")
			(net "GND")
		)
		(pad "2" smd rect
			(at 0 0.889 270)
			(size 0.508 0.508)
			(layers "F.Cu" "F.Mask" "F.Paste")
			(net "BMC_MIOZ")
		)
		(zone
			(layer "F.Cu")
			(hatch none 0.5)
			(connect_pads
				(clearance 0)
			)
			(min_thickness 0.25)
			(keepout
				(tracks not_allowed)
				(vias allowed)
				(pads allowed)
				(copperpour not_allowed)
				(footprints allowed)
			)
			(placement
				(enabled no)
				(sheetname "")
			)
			(fill
				(thermal_gap 0.5)
				(thermal_bridge_width 0.5)
				(island_removal_mode 0)
			)
			(polygon
				(pts
					(xy 427.99508 -36.32835) (xy 427.99508 -35.82035) (xy 428.37608 -35.82035) (xy 428.37608 -36.32835)
				)
			)
		)
		(zone
			(layer "F.Cu")
			(hatch none 0.5)
			(connect_pads
				(clearance 0)
			)
			(min_thickness 0.25)
			(keepout
				(tracks allowed)
				(vias not_allowed)
				(pads allowed)
				(copperpour not_allowed)
				(footprints allowed)
			)
			(placement
				(enabled no)
				(sheetname "")
			)
			(fill
				(thermal_gap 0.5)
				(thermal_bridge_width 0.5)
				(island_removal_mode 0)
			)
			(polygon
				(pts
					(xy 428.37608 -36.32835) (xy 428.37608 -35.82035) (xy 427.99508 -35.82035) (xy 427.99508 -36.32835)
				)
			)
		)
	)
	(footprint ""
		(layer "F.Cu")
		(at 9.585706 -3.355848 180)
		(property "Reference" "R1G9"
			(at 0 0 180)
			(layer "F.SilkS")
			(hide yes)
			(effects
				(font
					(size 1.27 1.27)
				)
			)
		)
		(property "Value" ""
			(at 0 0 180)
			(layer "F.Fab")
			(effects
				(font
					(size 1.27 1.27)
				)
			)
		)
		(duplicate_pad_numbers_are_jumpers no)
		(fp_rect
			(start 0.2794 0.9906)
			(end -0.2794 -0.1016)
			(stroke
				(width 0)
				(type default)
			)
			(fill no)
			(layer "F.CrtYd")
		)
		(fp_line
			(start 0.2794 0.9906)
			(end 0.2794 -0.1016)
			(stroke
				(width 0.1)
				(type default)
			)
			(layer "F.Fab")
		)
		(fp_line
			(start 0.2794 -0.1016)
			(end -0.2794 -0.1016)
			(stroke
				(width 0.1)
				(type default)
			)
			(layer "F.Fab")
		)
		(fp_line
			(start -0.2794 0.9906)
			(end 0.2794 0.9906)
			(stroke
				(width 0.1)
				(type default)
			)
			(layer "F.Fab")
		)
		(fp_line
			(start -0.2794 -0.1016)
			(end -0.2794 0.9906)
			(stroke
				(width 0.1)
				(type default)
			)
			(layer "F.Fab")
		)
		(pad "1" smd rect
			(at 0 0 180)
			(size 0.508 0.508)
			(layers "F.Cu" "F.Mask" "F.Paste")
			(net "SVID_ALERT_PVDDQ_GHJ")
		)
		(pad "2" smd rect
			(at 0 0.889 180)
			(size 0.508 0.508)
			(layers "F.Cu" "F.Mask" "F.Paste")
			(net "SVID_ALERT1_CPU1_R_N")
		)
		(zone
			(layer "F.Cu")
			(hatch none 0.5)
			(connect_pads
				(clearance 0)
			)
			(min_thickness 0.25)
			(keepout
				(tracks allowed)
				(vias not_allowed)
				(pads allowed)
				(copperpour not_allowed)
				(footprints allowed)
			)
			(placement
				(enabled no)
				(sheetname "")
			)
			(fill
				(thermal_gap 0.5)
				(thermal_bridge_width 0.5)
				(island_removal_mode 0)
			)
			(polygon
				(pts
					(xy 9.331706 -3.990848) (xy 9.331706 -3.609848) (xy 9.839706 -3.609848) (xy 9.839706 -3.990848)
				)
			)
		)
		(zone
			(layer "F.Cu")
			(hatch none 0.5)
			(connect_pads
				(clearance 0)
			)
			(min_thickness 0.25)
			(keepout
				(tracks not_allowed)
				(vias allowed)
				(pads allowed)
				(copperpour not_allowed)
				(footprints allowed)
			)
			(placement
				(enabled no)
				(sheetname "")
			)
			(fill
				(thermal_gap 0.5)
				(thermal_bridge_width 0.5)
				(island_removal_mode 0)
			)
			(polygon
				(pts
					(xy 9.331706 -3.990848) (xy 9.331706 -3.609848) (xy 9.839706 -3.609848) (xy 9.839706 -3.990848)
				)
			)
		)
	)
	(footprint ""
		(layer "F.Cu")
		(at 96.746568 -129.859024)
		(property "Reference" "C2B1"
			(at 0 0 0)
			(layer "F.SilkS")
			(hide yes)
			(effects
				(font
					(size 1.27 1.27)
				)
			)
		)
		(property "Value" ""
			(at 0 0 0)
			(layer "F.Fab")
			(effects
				(font
					(size 1.27 1.27)
				)
			)
		)
		(duplicate_pad_numbers_are_jumpers no)
		(fp_rect
			(start -0.500126 1.598422)
			(end 0.500126 -0.201422)
			(stroke
				(width 0)
				(type default)
			)
			(fill no)
			(layer "F.CrtYd")
		)
		(fp_line
			(start -0.500126 -0.201422)
			(end 0.500126 -0.201422)
			(stroke
				(width 0.1)
				(type default)
			)
			(layer "F.Fab")
		)
		(fp_line
			(start -0.500126 1.598422)
			(end -0.500126 -0.201422)
			(stroke
				(width 0.1)
				(type default)
			)
			(layer "F.Fab")
		)
		(fp_line
			(start 0.500126 -0.201422)
			(end 0.500126 1.598422)
			(stroke
				(width 0.1)
				(type default)
			)
			(layer "F.Fab")
		)
		(fp_line
			(start 0.500126 1.598422)
			(end -0.500126 1.598422)
			(stroke
				(width 0.1)
				(type default)
			)
			(layer "F.Fab")
		)
		(pad "1" smd rect
			(at 0 0 270)
			(size 0.889 0.9906)
			(layers "F.Cu" "F.Mask" "F.Paste")
			(net "PVDDQ_KLM")
		)
		(pad "2" smd rect
			(at 0 1.397 270)
			(size 0.889 0.9906)
			(layers "F.Cu" "F.Mask" "F.Paste")
			(net "GND")
		)
		(zone
			(layer "F.Cu")
			(hatch none 0.5)
			(connect_pads
				(clearance 0)
			)
			(min_thickness 0.25)
			(keepout
				(tracks allowed)
				(vias not_allowed)
				(pads allowed)
				(copperpour not_allowed)
				(footprints allowed)
			)
			(placement
				(enabled no)
				(sheetname "")
			)
			(fill
				(thermal_gap 0.5)
				(thermal_bridge_width 0.5)
				(island_removal_mode 0)
			)
			(polygon
				(pts
					(xy 96.251268 -128.906524) (xy 97.241868 -128.906524) (xy 97.241868 -129.414524) (xy 96.251268 -129.414524)
				)
			)
		)
		(zone
			(layer "F.Cu")
			(hatch none 0.5)
			(connect_pads
				(clearance 0)
			)
			(min_thickness 0.25)
			(keepout
				(tracks not_allowed)
				(vias allowed)
				(pads allowed)
				(copperpour not_allowed)
				(footprints allowed)
			)
			(placement
				(enabled no)
				(sheetname "")
			)
			(fill
				(thermal_gap 0.5)
				(thermal_bridge_width 0.5)
				(island_removal_mode 0)
			)
			(polygon
				(pts
					(xy 96.251268 -128.906524) (xy 97.241868 -128.906524) (xy 97.241868 -129.414524) (xy 96.251268 -129.414524)
				)
			)
		)
	)
	(footprint ""
		(layer "F.Cu")
		(at 198.912734 -97.679764 90)
		(property "Reference" "EU4C1"
			(at 3.893566 -0.538734 0)
			(unlocked yes)
			(layer "F.SilkS")
			(effects
				(font
					(size 0.7874 0.5842)
					(thickness 0.1524)
				)
			)
		)
		(property "Value" ""
			(at 0 0 90)
			(layer "F.Fab")
			(effects
				(font
					(size 1.27 1.27)
				)
			)
		)
		(duplicate_pad_numbers_are_jumpers no)
		(fp_line
			(start 2.9718 -3.5052)
			(end 2.9718 3.429)
			(stroke
				(width 0.1524)
				(type default)
			)
			(layer "F.SilkS")
		)
		(fp_line
			(start -3.0099 -3.5052)
			(end 2.9718 -3.5052)
			(stroke
				(width 0.1524)
				(type default)
			)
			(layer "F.SilkS")
		)
		(fp_line
			(start 2.9718 3.429)
			(end -3.0099 3.429)
			(stroke
				(width 0.1524)
				(type default)
			)
			(layer "F.SilkS")
		)
		(fp_line
			(start -3.0099 3.429)
			(end -3.0099 -3.5052)
			(stroke
				(width 0.1524)
				(type default)
			)
			(layer "F.SilkS")
		)
		(fp_circle
			(center -3.057398 -2.678684)
			(end -3.057398 -2.551684)
			(stroke
				(width 0.254)
				(type default)
			)
			(fill no)
			(layer "F.SilkS")
		)
		(fp_poly
			(pts
				(xy -2.9972 -3.4925) (xy -2.9972 -2.6924) (xy -2.1971 -3.4925)
			)
			(stroke
				(width 0)
				(type default)
			)
			(fill yes)
			(layer "F.SilkS")
		)
		(fp_poly
			(pts
				(xy -2.549906 -3.050032) (xy -2.549906 3.050032) (xy 2.549906 3.050032) (xy 2.549906 -3.050032)
			)
			(stroke
				(width 0)
				(type default)
			)
			(fill no)
			(layer "F.CrtYd")
		)
		(fp_line
			(start 2.549906 -3.050032)
			(end 2.549906 3.050032)
			(stroke
				(width 0.1)
				(type default)
			)
			(layer "F.Fab")
		)
		(fp_line
			(start -2.549906 -3.050032)
			(end 2.549906 -3.050032)
			(stroke
				(width 0.1)
				(type default)
			)
			(layer "F.Fab")
		)
		(fp_line
			(start 2.549906 3.050032)
			(end -2.549906 3.050032)
			(stroke
				(width 0.1)
				(type default)
			)
			(layer "F.Fab")
		)
		(fp_line
			(start -2.549906 3.050032)
			(end -2.549906 -3.050032)
			(stroke
				(width 0.1)
				(type default)
			)
			(layer "F.Fab")
		)
		(fp_circle
			(center -3.057398 -2.678684)
			(end -3.057398 -2.551684)
			(stroke
				(width 0.254)
				(type default)
			)
			(fill no)
			(layer "F.Fab")
		)
		(pad "1" smd rect
			(at -2.39522 -2.279904 90)
			(size 0.7112 0.254)
			(layers "F.Cu" "F.Mask" "F.Paste")
			(net "PVSA_CPU0")
		)
		(pad "2" smd rect
			(at -2.39522 -1.83007 90)
			(size 0.7112 0.254)
			(layers "F.Cu" "F.Mask" "F.Paste")
			(net "GND")
		)
		(pad "3" smd rect
			(at -2.39522 -1.379982 90)
			(size 0.7112 0.254)
			(layers "F.Cu" "F.Mask" "F.Paste")
			(net "VR_PVSA_CPU0_VCIN")
		)
		(pad "4" smd rect
			(at -2.39522 -0.929894 90)
			(size 0.7112 0.254)
			(layers "F.Cu" "F.Mask" "F.Paste")
			(net "P5V_STBY")
		)
		(pad "5" smd rect
			(at -2.39522 -0.48006 90)
			(size 0.7112 0.254)
			(layers "F.Cu" "F.Mask" "F.Paste")
			(net "GND")
		)
		(pad "6" smd rect
			(at -2.39522 -0.029972 90)
			(size 0.7112 0.254)
			(layers "F.Cu" "F.Mask" "F.Paste")
			(net "TP_PVSA_CPU0_GL_0")
		)
		(pad "7" smd custom
			(at 0.016764 1.145032 90)
			(size 0.53975 0.53975)
			(layers "F.Cu" "F.Mask" "F.Paste")
			(net "GND")
			(options
				(clearance outline)
				(anchor circle)
			)
			(primitives
				(gr_poly
					(pts
						(xy -2.7051 1.0795) (xy -2.7051 -0.3683) (xy -0.9271 -0.3683) (xy -0.9271 -1.0795) (xy 2.7051 -1.0795)
						(xy 2.7051 1.0795)
					)
					(width 0)
					(fill yes)
				)
			)
		)
		(pad "10" smd rect
			(at -0.008382 2.874772 90)
			(size 4.3434 0.6096)
			(layers "F.Cu" "F.Mask" "F.Paste")
			(net "VR_PVSA_CPU0_PHASE_SW")
		)
		(pad "25" smd rect
			(at 1.548384 -1.283208 90)
			(size 2.3368 2.0066)
			(layers "F.Cu" "F.Mask" "F.Paste")
			(net "VR_FET_SW_P12V_STBY_PVCCIN_CPU0")
		)
		(pad "30" smd rect
			(at 2.050034 -2.895092 90)
			(size 0.254 0.7112)
			(layers "F.Cu" "F.Mask" "F.Paste")
			(net "VR_FET_SW_P12V_STBY_PVCCIN_CPU0")
		)
		(pad "31" smd rect
			(at 1.599946 -2.895092 90)
			(size 0.254 0.7112)
			(layers "F.Cu" "F.Mask" "F.Paste")
			(net "Net_375")
		)
		(pad "32" smd rect
			(at 1.150112 -2.895092 90)
			(size 0.254 0.7112)
			(layers "F.Cu" "F.Mask" "F.Paste")
			(net "VR_PVSA_CPU0_PHASE")
		)
		(pad "33" smd rect
			(at 0.700024 -2.895092 90)
			(size 0.254 0.7112)
			(layers "F.Cu" "F.Mask" "F.Paste")
			(net "VR_PVSA_CPU0_BOOT_R")
		)
		(pad "34" smd rect
			(at 0.249936 -2.895092 90)
			(size 0.254 0.7112)
			(layers "F.Cu" "F.Mask" "F.Paste")
			(net "VR_PVSA_CPU0_PWM")
		)
		(pad "35" smd rect
			(at -0.199898 -2.895092 90)
			(size 0.254 0.7112)
			(layers "F.Cu" "F.Mask" "F.Paste")
			(net "P5V_STBY")
		)
		(pad "36" smd rect
			(at -0.649986 -2.895092 90)
			(size 0.254 0.7112)
			(layers "F.Cu" "F.Mask" "F.Paste")
			(net "A_TSENSE_PVSA_CPU0")
		)
		(pad "37" smd rect
			(at -1.100074 -2.895092 90)
			(size 0.254 0.7112)
			(layers "F.Cu" "F.Mask" "F.Paste")
			(net "VR_PVSA_CPU0_OCSET")
		)
		(pad "38" smd rect
			(at -1.549908 -2.895092 90)
			(size 0.254 0.7112)
			(layers "F.Cu" "F.Mask" "F.Paste")
			(net "ISENSE_PVSA_CPU0_IMON")
		)
		(pad "39" smd rect
			(at -1.999996 -2.895092 90)
			(size 0.254 0.7112)
			(layers "F.Cu" "F.Mask" "F.Paste")
			(net "VR_PVSA_CPU0_BIREF1")
		)
		(pad "40" smd rect
			(at -0.871728 -1.283208 90)
			(size 1.8034 2.0066)
			(layers "F.Cu" "F.Mask" "F.Paste")
			(net "GND")
		)
		(pad "41" smd rect
			(at -1.533906 0.247904 90)
			(size 0.508 0.3556)
			(layers "F.Cu" "F.Mask" "F.Paste")
			(net "TP_PVSA_CPU0_GL_1")
		)
	)
)
